(kicad_pcb
	(version 20260206)
	(generator "pcbnew")
	(generator_version "10.0")
	(general
		(thickness 1.6)
		(legacy_teardrops no)
	)
	(paper "A4")
	(title_block
		(title "Wiwynn_Tioga_Pass_MB.brd")
		(comment 1 "Tioga Pass / footprint 190 of 4770 (U2D1), pads 2187-2294 of 3647")
	)
	(layers
		(0 "F.Cu" signal "TOP")
		(4 "In1.Cu" signal "L2GND")
		(6 "In2.Cu" signal "L3")
		(8 "In3.Cu" signal "L4GND")
		(10 "In4.Cu" signal "L5")
		(12 "In5.Cu" signal "L6GND")
		(14 "In6.Cu" signal "L7VCC")
		(16 "In7.Cu" signal "L8VCC")
		(18 "In8.Cu" signal "L9GND")
		(20 "In9.Cu" signal "L10")
		(22 "In10.Cu" signal "L11GND")
		(24 "In11.Cu" signal "L12")
		(26 "In12.Cu" signal "L13GND")
		(2 "B.Cu" signal "BOTTOM")
		(9 "F.Adhes" user "F.Adhesive")
		(11 "B.Adhes" user "B.Adhesive")
		(13 "F.Paste" user "Package Geometry/Pastemask Top")
		(15 "B.Paste" user "Package Geometry/Pastemask Bottom")
		(5 "F.SilkS" user "Ref Des/Silkscreen Top")
		(7 "B.SilkS" user "Ref Des/Silkscreen Bottom")
		(1 "F.Mask" user "Board Geometry/Soldermask Top")
		(3 "B.Mask" user "Board Geometry/Soldermask Bottom")
		(17 "Dwgs.User" user "User.Drawings")
		(19 "Cmts.User" user "User.Comments")
		(21 "Eco1.User" user "User.Eco1")
		(23 "Eco2.User" user "User.Eco2")
		(25 "Edge.Cuts" user "Board Geometry/Outline")
		(27 "Margin" user)
		(31 "F.CrtYd" user "Package Geometry/Place Bound Top")
		(29 "B.CrtYd" user "Package Geometry/Place Bound Bottom")
		(35 "F.Fab" user "Ref Des/Assembly Top")
		(33 "B.Fab" user "Ref Des/Assembly Bottom")
	)
	(footprint ""
		(layer "F.Cu")
		(at 104.99979 -76.550012 180)
		(property "Reference" "U2D1"
			(at 25.19299 30.484318 0)
			(unlocked yes)
			(layer "F.SilkS")
			(effects
				(font
					(size 0.7874 0.5842)
					(thickness 0.1524)
				)
			)
		)
		(property "Value" ""
			(at 0 0 180)
			(layer "F.Fab")
			(effects
				(font
					(size 1.27 1.27)
				)
			)
		)
		(duplicate_pad_numbers_are_jumpers no)
		(pad "DF75" smd circle
			(at 27.806904 15.197074)
			(size 0.4318 0.4318)
			(layers "F.Cu" "F.Mask" "F.Paste")
			(net "M_M_DQS_DN<10>")
		)
		(pad "DF77" smd circle
			(at 29.523944 15.197074)
			(size 0.4318 0.4318)
			(layers "F.Cu" "F.Mask" "F.Paste")
			(net "M_M_DQ<14>")
		)
		(pad "DF79" smd circle
			(at 31.240984 15.197074)
			(size 0.4318 0.4318)
			(layers "F.Cu" "F.Mask" "F.Paste")
			(net "GND")
		)
		(pad "DF81" smd circle
			(at 32.958024 15.197074)
			(size 0.4318 0.4318)
			(layers "F.Cu" "F.Mask" "F.Paste")
			(net "M_L_DQ<11>")
		)
		(pad "DF83" smd circle
			(at 34.675064 15.197074)
			(size 0.4318 0.4318)
			(layers "F.Cu" "F.Mask" "F.Paste")
			(net "GND")
		)
		(pad "DF85" smd custom
			(at 36.392104 15.197074 270)
			(size 0.10795 0.10795)
			(layers "F.Cu" "F.Mask" "F.Paste")
			(net "GND")
			(options
				(clearance outline)
				(anchor circle)
			)
			(primitives
				(gr_poly
					(pts
						(arc
							(start 0.2159 -0.0381)
							(mid 0 -0.254)
							(end -0.2159 -0.0381)
						)
						(arc
							(start -0.2159 0.0381)
							(mid 0 0.254)
							(end 0.2159 0.0381)
						)
					)
					(width 0)
					(fill yes)
				)
			)
		)
		(pad "DG2" smd custom
			(at -36.392104 17.492726 90)
			(size 0.10795 0.10795)
			(layers "F.Cu" "F.Mask" "F.Paste")
			(net "GND")
			(options
				(clearance outline)
				(anchor circle)
			)
			(primitives
				(gr_poly
					(pts
						(arc
							(start 0.2159 -0.0381)
							(mid 0 -0.254)
							(end -0.2159 -0.0381)
						)
						(arc
							(start -0.2159 0.0381)
							(mid 0 0.254)
							(end 0.2159 0.0381)
						)
					)
					(width 0)
					(fill yes)
				)
			)
		)
		(pad "DG4" smd circle
			(at -34.675064 17.492726)
			(size 0.4318 0.4318)
			(layers "F.Cu" "F.Mask" "F.Paste")
			(net "TP_P3E_CPU1_PE1_MP_TXN<4>")
		)
		(pad "DG6" smd circle
			(at -32.958024 17.492726)
			(size 0.4318 0.4318)
			(layers "F.Cu" "F.Mask" "F.Paste")
			(net "P3E_CPU1_PE3_MP_TXP<12>")
		)
		(pad "DG8" smd circle
			(at -31.240984 17.492726)
			(size 0.4318 0.4318)
			(layers "F.Cu" "F.Mask" "F.Paste")
			(net "PVCCIO_CPU1")
		)
		(pad "DG10" smd circle
			(at -29.523944 17.492726)
			(size 0.4318 0.4318)
			(layers "F.Cu" "F.Mask" "F.Paste")
			(net "P3E_CPU1_PE3_MP_RXN<11>")
		)
		(pad "DG12" smd circle
			(at -27.806904 17.492726)
			(size 0.4318 0.4318)
			(layers "F.Cu" "F.Mask" "F.Paste")
			(net "P3E_CPU1_PE3_MP_RXN<10>")
		)
		(pad "DG14" smd circle
			(at -26.090118 17.492726)
			(size 0.4318 0.4318)
			(layers "F.Cu" "F.Mask" "F.Paste")
			(net "GND")
		)
		(pad "DG16" smd circle
			(at -24.373078 17.492726)
			(size 0.4318 0.4318)
			(layers "F.Cu" "F.Mask" "F.Paste")
			(net "GND")
		)
		(pad "DG18" smd circle
			(at -22.656038 17.492726)
			(size 0.4318 0.4318)
			(layers "F.Cu" "F.Mask" "F.Paste")
			(net "TP_CPU1_UPI2_RSVD_CM13")
		)
		(pad "DG20" smd circle
			(at -20.938998 17.492726)
			(size 0.4318 0.4318)
			(layers "F.Cu" "F.Mask" "F.Paste")
			(net "TP_CPU1_UPI2_RSVD_CH11")
		)
		(pad "DG22" smd circle
			(at -19.221958 17.492726)
			(size 0.4318 0.4318)
			(layers "F.Cu" "F.Mask" "F.Paste")
			(net "GND")
		)
		(pad "DG24" smd circle
			(at -17.504918 17.492726)
			(size 0.4318 0.4318)
			(layers "F.Cu" "F.Mask" "F.Paste")
			(net "GND")
		)
		(pad "DG26" smd circle
			(at -15.787878 17.492726)
			(size 0.4318 0.4318)
			(layers "F.Cu" "F.Mask" "F.Paste")
			(net "M_L_DQS_DN<16>")
		)
		(pad "DG28" smd circle
			(at -14.071092 17.492726)
			(size 0.4318 0.4318)
			(layers "F.Cu" "F.Mask" "F.Paste")
			(net "M_L_DQ<60>")
		)
		(pad "DG30" smd circle
			(at -12.354052 17.492726)
			(size 0.4318 0.4318)
			(layers "F.Cu" "F.Mask" "F.Paste")
			(net "M_M_DQ<42>")
		)
		(pad "DG32" smd circle
			(at -10.637012 17.492726)
			(size 0.4318 0.4318)
			(layers "F.Cu" "F.Mask" "F.Paste")
			(net "M_M_DQS_DN<14>")
		)
		(pad "DG34" smd circle
			(at -8.919972 17.492726)
			(size 0.4318 0.4318)
			(layers "F.Cu" "F.Mask" "F.Paste")
			(net "M_M_DQ<44>")
		)
		(pad "DG36" smd circle
			(at -7.202932 17.492726)
			(size 0.4318 0.4318)
			(layers "F.Cu" "F.Mask" "F.Paste")
			(net "TP_CPU1_RSVD_44")
		)
		(pad "DG38" smd circle
			(at -5.485892 17.492726)
			(size 0.4318 0.4318)
			(layers "F.Cu" "F.Mask" "F.Paste")
			(net "M_M_DQ<35>")
		)
		(pad "DG40" smd circle
			(at -3.769106 17.492726)
			(size 0.4318 0.4318)
			(layers "F.Cu" "F.Mask" "F.Paste")
			(net "M_M_DQS_DN<4>")
		)
		(pad "DG42" smd circle
			(at -2.052066 17.492726)
			(size 0.4318 0.4318)
			(layers "F.Cu" "F.Mask" "F.Paste")
			(net "M_M_DQ<33>")
		)
		(pad "DG44" smd circle
			(at 1.193546 15.692628)
			(size 0.508 0.508)
			(layers "F.Cu" "F.Mask" "F.Paste")
			(net "SVID_CLK1_CPU1")
		)
		(pad "DG46" smd circle
			(at 2.910586 15.692628)
			(size 0.4318 0.4318)
			(layers "F.Cu" "F.Mask" "F.Paste")
			(net "M_M_CS_N<3>")
		)
		(pad "DG48" smd circle
			(at 4.627626 15.692628)
			(size 0.4318 0.4318)
			(layers "F.Cu" "F.Mask" "F.Paste")
			(net "M_M_ODT<1>")
		)
		(pad "DG50" smd circle
			(at 6.344412 15.692628)
			(size 0.4318 0.4318)
			(layers "F.Cu" "F.Mask" "F.Paste")
			(net "M_M_ODT<0>")
		)
		(pad "DG52" smd circle
			(at 8.061452 15.692628)
			(size 0.4318 0.4318)
			(layers "F.Cu" "F.Mask" "F.Paste")
			(net "M_M_MA<16>")
		)
		(pad "DG54" smd circle
			(at 9.778492 15.692628)
			(size 0.4318 0.4318)
			(layers "F.Cu" "F.Mask" "F.Paste")
			(net "M_M_CLK_DP<1>")
		)
		(pad "DG56" smd circle
			(at 11.495532 15.692628)
			(size 0.4318 0.4318)
			(layers "F.Cu" "F.Mask" "F.Paste")
			(net "M_M_CLK_DP<3>")
		)
		(pad "DG58" smd circle
			(at 13.212572 15.692628)
			(size 0.4318 0.4318)
			(layers "F.Cu" "F.Mask" "F.Paste")
			(net "M_M_MA<3>")
		)
		(pad "DG60" smd circle
			(at 14.929612 15.692628)
			(size 0.4318 0.4318)
			(layers "F.Cu" "F.Mask" "F.Paste")
			(net "M_M_MA<12>")
		)
		(pad "DG62" smd circle
			(at 16.646398 15.692628)
			(size 0.4318 0.4318)
			(layers "F.Cu" "F.Mask" "F.Paste")
			(net "M_M_CKE<0>")
		)
		(pad "DG64" smd circle
			(at 18.363438 15.692628)
			(size 0.4318 0.4318)
			(layers "F.Cu" "F.Mask" "F.Paste")
			(net "TP_CPU1_RSVD_43")
		)
		(pad "DG66" smd circle
			(at 20.080478 15.692628)
			(size 0.4318 0.4318)
			(layers "F.Cu" "F.Mask" "F.Paste")
			(net "GND")
		)
		(pad "DG68" smd circle
			(at 21.797518 15.692628)
			(size 0.4318 0.4318)
			(layers "F.Cu" "F.Mask" "F.Paste")
			(net "GND")
		)
		(pad "DG70" smd circle
			(at 23.514558 15.692628)
			(size 0.4318 0.4318)
			(layers "F.Cu" "F.Mask" "F.Paste")
			(net "M_M_DQ<16>")
		)
		(pad "DG72" smd circle
			(at 25.231598 15.692628)
			(size 0.4318 0.4318)
			(layers "F.Cu" "F.Mask" "F.Paste")
			(net "M_M_DQ<21>")
		)
		(pad "DG74" smd circle
			(at 26.948384 15.692628)
			(size 0.4318 0.4318)
			(layers "F.Cu" "F.Mask" "F.Paste")
			(net "M_M_DQS_DP<10>")
		)
		(pad "DG76" smd circle
			(at 28.665424 15.692628)
			(size 0.4318 0.4318)
			(layers "F.Cu" "F.Mask" "F.Paste")
			(net "GND")
		)
		(pad "DG78" smd circle
			(at 30.382464 15.692628)
			(size 0.4318 0.4318)
			(layers "F.Cu" "F.Mask" "F.Paste")
			(net "GND")
		)
		(pad "DG80" smd circle
			(at 32.099504 15.692628)
			(size 0.4318 0.4318)
			(layers "F.Cu" "F.Mask" "F.Paste")
			(net "GND")
		)
		(pad "DG82" smd circle
			(at 33.816544 15.692628)
			(size 0.4318 0.4318)
			(layers "F.Cu" "F.Mask" "F.Paste")
			(net "GND")
		)
		(pad "DG84" smd circle
			(at 35.533584 15.692628)
			(size 0.4318 0.4318)
			(layers "F.Cu" "F.Mask" "F.Paste")
			(net "M_K_DQ<8>")
		)
		(pad "DH3" smd circle
			(at -35.533584 17.988026)
			(size 0.4318 0.4318)
			(layers "F.Cu" "F.Mask" "F.Paste")
			(net "TP_P3E_CPU1_PE1_MP_TXP<5>")
		)
		(pad "DH5" smd circle
			(at -33.816544 17.988026)
			(size 0.4318 0.4318)
			(layers "F.Cu" "F.Mask" "F.Paste")
			(net "P3E_CPU1_PE3_MP_TXP<11>")
		)
		(pad "DH7" smd circle
			(at -32.099504 17.988026)
			(size 0.4318 0.4318)
			(layers "F.Cu" "F.Mask" "F.Paste")
			(net "PVCCIO_CPU1")
		)
		(pad "DH9" smd circle
			(at -30.382464 17.988026)
			(size 0.4318 0.4318)
			(layers "F.Cu" "F.Mask" "F.Paste")
			(net "TP_P3E_CPU1_PE1_MP_RXN<5>")
		)
		(pad "DH11" smd circle
			(at -28.665424 17.988026)
			(size 0.4318 0.4318)
			(layers "F.Cu" "F.Mask" "F.Paste")
			(net "P3E_CPU1_PE3_MP_RXP<9>")
		)
		(pad "DH13" smd circle
			(at -26.948384 17.988026)
			(size 0.4318 0.4318)
			(layers "F.Cu" "F.Mask" "F.Paste")
			(net "GND")
		)
		(pad "DH15" smd circle
			(at -25.231598 17.988026)
			(size 0.4318 0.4318)
			(layers "F.Cu" "F.Mask" "F.Paste")
			(net "GND")
		)
		(pad "DH17" smd circle
			(at -23.514558 17.988026)
			(size 0.4318 0.4318)
			(layers "F.Cu" "F.Mask" "F.Paste")
			(net "TP_CPU1_UPI2_RSVD_CH13")
		)
		(pad "DH19" smd circle
			(at -21.797518 17.988026)
			(size 0.4318 0.4318)
			(layers "F.Cu" "F.Mask" "F.Paste")
			(net "TP_CPU1_UPI2_RSVD_CF13")
		)
		(pad "DH21" smd circle
			(at -20.080478 17.988026)
			(size 0.4318 0.4318)
			(layers "F.Cu" "F.Mask" "F.Paste")
			(net "GND")
		)
		(pad "DH23" smd circle
			(at -18.363438 17.988026)
			(size 0.4318 0.4318)
			(layers "F.Cu" "F.Mask" "F.Paste")
			(net "GND")
		)
		(pad "DH25" smd circle
			(at -16.646398 17.988026)
			(size 0.4318 0.4318)
			(layers "F.Cu" "F.Mask" "F.Paste")
			(net "GND")
		)
		(pad "DH27" smd circle
			(at -14.929612 17.988026)
			(size 0.4318 0.4318)
			(layers "F.Cu" "F.Mask" "F.Paste")
			(net "GND")
		)
		(pad "DH29" smd circle
			(at -13.212572 17.988026)
			(size 0.4318 0.4318)
			(layers "F.Cu" "F.Mask" "F.Paste")
			(net "GND")
		)
		(pad "DH31" smd circle
			(at -11.495532 17.988026)
			(size 0.4318 0.4318)
			(layers "F.Cu" "F.Mask" "F.Paste")
			(net "GND")
		)
		(pad "DH33" smd circle
			(at -9.778492 17.988026)
			(size 0.4318 0.4318)
			(layers "F.Cu" "F.Mask" "F.Paste")
			(net "GND")
		)
		(pad "DH35" smd circle
			(at -8.061452 17.988026)
			(size 0.4318 0.4318)
			(layers "F.Cu" "F.Mask" "F.Paste")
			(net "GND")
		)
		(pad "DH37" smd circle
			(at -6.344412 17.988026)
			(size 0.4318 0.4318)
			(layers "F.Cu" "F.Mask" "F.Paste")
			(net "GND")
		)
		(pad "DH39" smd circle
			(at -4.627626 17.988026)
			(size 0.4318 0.4318)
			(layers "F.Cu" "F.Mask" "F.Paste")
			(net "M_M_DQ<39>")
		)
		(pad "DH41" smd circle
			(at -2.910586 17.988026)
			(size 0.4318 0.4318)
			(layers "F.Cu" "F.Mask" "F.Paste")
			(net "GND")
		)
		(pad "DH45" smd circle
			(at 2.052066 16.187674)
			(size 0.4318 0.4318)
			(layers "F.Cu" "F.Mask" "F.Paste")
			(net "PVDDQ_KLM")
		)
		(pad "DH47" smd circle
			(at 3.769106 16.187674)
			(size 0.4318 0.4318)
			(layers "F.Cu" "F.Mask" "F.Paste")
			(net "PVDDQ_KLM")
		)
		(pad "DH49" smd circle
			(at 5.485892 16.187674)
			(size 0.4318 0.4318)
			(layers "F.Cu" "F.Mask" "F.Paste")
			(net "PVDDQ_KLM")
		)
		(pad "DH51" smd circle
			(at 7.202932 16.187674)
			(size 0.4318 0.4318)
			(layers "F.Cu" "F.Mask" "F.Paste")
			(net "PVDDQ_KLM")
		)
		(pad "DH53" smd circle
			(at 8.919972 16.187674)
			(size 0.4318 0.4318)
			(layers "F.Cu" "F.Mask" "F.Paste")
			(net "PVDDQ_KLM")
		)
		(pad "DH55" smd circle
			(at 10.637012 16.187674)
			(size 0.4318 0.4318)
			(layers "F.Cu" "F.Mask" "F.Paste")
			(net "PVDDQ_KLM")
		)
		(pad "DH57" smd circle
			(at 12.354052 16.187674)
			(size 0.4318 0.4318)
			(layers "F.Cu" "F.Mask" "F.Paste")
			(net "PVDDQ_KLM")
		)
		(pad "DH59" smd circle
			(at 14.071092 16.187674)
			(size 0.4318 0.4318)
			(layers "F.Cu" "F.Mask" "F.Paste")
			(net "PVDDQ_KLM")
		)
		(pad "DH61" smd circle
			(at 15.787878 16.187674)
			(size 0.4318 0.4318)
			(layers "F.Cu" "F.Mask" "F.Paste")
			(net "PVDDQ_KLM")
		)
		(pad "DH63" smd circle
			(at 17.504918 16.187674)
			(size 0.4318 0.4318)
			(layers "F.Cu" "F.Mask" "F.Paste")
			(net "PVDDQ_KLM")
		)
		(pad "DH65" smd circle
			(at 19.221958 16.187674)
			(size 0.4318 0.4318)
			(layers "F.Cu" "F.Mask" "F.Paste")
			(net "TP_CPU1_RSVD_42")
		)
		(pad "DH67" smd circle
			(at 20.938998 16.187674)
			(size 0.4318 0.4318)
			(layers "F.Cu" "F.Mask" "F.Paste")
			(net "GND")
		)
		(pad "DH69" smd circle
			(at 22.656038 16.187674)
			(size 0.4318 0.4318)
			(layers "F.Cu" "F.Mask" "F.Paste")
			(net "M_M_DQS_DP<11>")
		)
		(pad "DH71" smd circle
			(at 24.373078 16.187674)
			(size 0.4318 0.4318)
			(layers "F.Cu" "F.Mask" "F.Paste")
			(net "GND")
		)
		(pad "DH73" smd circle
			(at 26.090118 16.187674)
			(size 0.4318 0.4318)
			(layers "F.Cu" "F.Mask" "F.Paste")
			(net "GND")
		)
		(pad "DH75" smd circle
			(at 27.806904 16.187674)
			(size 0.4318 0.4318)
			(layers "F.Cu" "F.Mask" "F.Paste")
			(net "M_M_DQ<10>")
		)
		(pad "DH77" smd circle
			(at 29.523944 16.187674)
			(size 0.4318 0.4318)
			(layers "F.Cu" "F.Mask" "F.Paste")
			(net "M_M_DQ<15>")
		)
		(pad "DH79" smd circle
			(at 31.240984 16.187674)
			(size 0.4318 0.4318)
			(layers "F.Cu" "F.Mask" "F.Paste")
			(net "GND")
		)
		(pad "DH81" smd circle
			(at 32.958024 16.187674)
			(size 0.4318 0.4318)
			(layers "F.Cu" "F.Mask" "F.Paste")
			(net "GND")
		)
		(pad "DH83" smd circle
			(at 34.675064 16.187674)
			(size 0.4318 0.4318)
			(layers "F.Cu" "F.Mask" "F.Paste")
			(net "GND")
		)
		(pad "DH85" smd custom
			(at 36.392104 16.187674 270)
			(size 0.10795 0.10795)
			(layers "F.Cu" "F.Mask" "F.Paste")
			(net "M_K_DQ<9>")
			(options
				(clearance outline)
				(anchor circle)
			)
			(primitives
				(gr_poly
					(pts
						(arc
							(start 0.2159 -0.0381)
							(mid 0 -0.254)
							(end -0.2159 -0.0381)
						)
						(arc
							(start -0.2159 0.0381)
							(mid 0 0.254)
							(end 0.2159 0.0381)
						)
					)
					(width 0)
					(fill yes)
				)
			)
		)
		(pad "DJ2" smd custom
			(at -36.392104 18.483072 90)
			(size 0.10795 0.10795)
			(layers "F.Cu" "F.Mask" "F.Paste")
			(net "GND")
			(options
				(clearance outline)
				(anchor circle)
			)
			(primitives
				(gr_poly
					(pts
						(arc
							(start 0.2159 -0.0381)
							(mid 0 -0.254)
							(end -0.2159 -0.0381)
						)
						(arc
							(start -0.2159 0.0381)
							(mid 0 0.254)
							(end 0.2159 0.0381)
						)
					)
					(width 0)
					(fill yes)
				)
			)
		)
		(pad "DJ4" smd circle
			(at -34.675064 18.483072)
			(size 0.4318 0.4318)
			(layers "F.Cu" "F.Mask" "F.Paste")
			(net "P3E_CPU1_PE3_MP_TXN<11>")
		)
		(pad "DJ6" smd circle
			(at -32.958024 18.483072)
			(size 0.4318 0.4318)
			(layers "F.Cu" "F.Mask" "F.Paste")
			(net "P3E_CPU1_PE3_MP_TXN<12>")
		)
		(pad "DJ8" smd circle
			(at -31.240984 18.483072)
			(size 0.4318 0.4318)
			(layers "F.Cu" "F.Mask" "F.Paste")
			(net "TP_P3E_CPU1_PE1_MP_RXP<6>")
		)
		(pad "DJ10" smd circle
			(at -29.523944 18.483072)
			(size 0.4318 0.4318)
			(layers "F.Cu" "F.Mask" "F.Paste")
			(net "GND")
		)
		(pad "DJ12" smd circle
			(at -27.806904 18.483072)
			(size 0.4318 0.4318)
			(layers "F.Cu" "F.Mask" "F.Paste")
			(net "P3E_CPU1_PE3_MP_RXN<9>")
		)
		(pad "DJ14" smd circle
			(at -26.090118 18.483072)
			(size 0.4318 0.4318)
			(layers "F.Cu" "F.Mask" "F.Paste")
			(net "P3E_CPU1_PE3_MP_RXP<7>")
		)
		(pad "DJ16" smd circle
			(at -24.373078 18.483072)
			(size 0.4318 0.4318)
			(layers "F.Cu" "F.Mask" "F.Paste")
			(net "PVCCIO_CPU1")
		)
		(pad "DJ18" smd circle
			(at -22.656038 18.483072)
			(size 0.4318 0.4318)
			(layers "F.Cu" "F.Mask" "F.Paste")
			(net "TP_CPU1_UPI2_RSVD_CG12")
		)
		(pad "DJ20" smd circle
			(at -20.938998 18.483072)
			(size 0.4318 0.4318)
			(layers "F.Cu" "F.Mask" "F.Paste")
			(net "TP_CPU1_UPI2_RSVD_CF11")
		)
		(pad "DJ22" smd circle
			(at -19.221958 18.483072)
			(size 0.4318 0.4318)
			(layers "F.Cu" "F.Mask" "F.Paste")
			(net "GND")
		)
		(pad "DJ24" smd circle
			(at -17.504918 18.483072)
			(size 0.4318 0.4318)
			(layers "F.Cu" "F.Mask" "F.Paste")
			(net "M_L_DQ<59>")
		)
		(pad "DJ26" smd circle
			(at -15.787878 18.483072)
			(size 0.4318 0.4318)
			(layers "F.Cu" "F.Mask" "F.Paste")
			(net "M_L_DQS_DP<7>")
		)
		(pad "DJ28" smd circle
			(at -14.071092 18.483072)
			(size 0.4318 0.4318)
			(layers "F.Cu" "F.Mask" "F.Paste")
			(net "M_L_DQ<61>")
		)
		(pad "DJ30" smd circle
			(at -12.354052 18.483072)
			(size 0.4318 0.4318)
			(layers "F.Cu" "F.Mask" "F.Paste")
			(net "M_M_DQ<43>")
		)
		(pad "DJ32" smd circle
			(at -10.637012 18.483072)
			(size 0.4318 0.4318)
			(layers "F.Cu" "F.Mask" "F.Paste")
			(net "M_M_DQS_DP<5>")
		)
		(pad "DJ34" smd circle
			(at -8.919972 18.483072)
			(size 0.4318 0.4318)
			(layers "F.Cu" "F.Mask" "F.Paste")
			(net "M_M_DQ<45>")
		)
		(pad "DJ36" smd circle
			(at -7.202932 18.483072)
			(size 0.4318 0.4318)
			(layers "F.Cu" "F.Mask" "F.Paste")
			(net "TP_CPU1_RSVD_41")
		)
		(pad "DJ38" smd circle
			(at -5.485892 18.483072)
			(size 0.4318 0.4318)
			(layers "F.Cu" "F.Mask" "F.Paste")
			(net "GND")
		)
	)
)
